(kicad_pcb
	(version 20260206)
	(generator "pcbnew")
	(generator_version "10.0")
	(general
		(thickness 1.6)
		(legacy_teardrops no)
	)
	(paper "A4")
	(title_block
		(title "04192023_DAF0TMB3IC0_F0TG_MB_C_brd_V02_OCP.brd")
		(comment 1 "Grand Teton / footprints 2252-2256 of 8354")
	)
	(layers
		(0 "F.Cu" signal "TOP")
		(4 "In1.Cu" signal "GND")
		(6 "In2.Cu" signal "IN1")
		(8 "In3.Cu" signal "GND1")
		(10 "In4.Cu" signal "IN2")
		(12 "In5.Cu" signal "GND2")
		(14 "In6.Cu" signal "IN3")
		(16 "In7.Cu" signal "GND3")
		(18 "In8.Cu" signal "VCC")
		(20 "In9.Cu" signal "VCC1")
		(22 "In10.Cu" signal "GND4")
		(24 "In11.Cu" signal "IN4")
		(26 "In12.Cu" signal "GND5")
		(28 "In13.Cu" signal "IN5")
		(30 "In14.Cu" signal "GND6")
		(32 "In15.Cu" signal "IN6")
		(34 "In16.Cu" signal "GND7")
		(2 "B.Cu" signal "BOTTOM")
		(9 "F.Adhes" user "F.Adhesive")
		(11 "B.Adhes" user "B.Adhesive")
		(13 "F.Paste" user "Package Geometry/Pastemask Top")
		(15 "B.Paste" user "Package Geometry/Pastemask Bottom")
		(5 "F.SilkS" user "Ref Des/Silkscreen Top")
		(7 "B.SilkS" user "Ref Des/Silkscreen Bottom")
		(1 "F.Mask" user "Board Geometry/Soldermask Top")
		(3 "B.Mask" user "Board Geometry/Soldermask Bottom")
		(17 "Dwgs.User" user "User.Drawings")
		(19 "Cmts.User" user "User.Comments")
		(21 "Eco1.User" user "User.Eco1")
		(23 "Eco2.User" user "User.Eco2")
		(25 "Edge.Cuts" user "Board Geometry/Outline")
		(27 "Margin" user)
		(31 "F.CrtYd" user "Package Geometry/Place Bound Top")
		(29 "B.CrtYd" user "Package Geometry/Place Bound Bottom")
		(35 "F.Fab" user "Ref Des/Assembly Top")
		(33 "B.Fab" user "Ref Des/Assembly Bottom")
	)
	(footprint ""
		(layer "F.Cu")
		(at 105.84561 -65.57391)
		(property "Reference" "R6218"
			(at 0 0 0)
			(layer "F.SilkS")
			(hide yes)
			(effects
				(font
					(size 1.27 1.27)
				)
			)
		)
		(property "Value" ""
			(at 0 0 0)
			(layer "F.Fab")
			(effects
				(font
					(size 1.27 1.27)
				)
			)
		)
		(duplicate_pad_numbers_are_jumpers no)
		(fp_line
			(start -0.7874 -0.4064)
			(end 0.7874 -0.4064)
			(stroke
				(width 0.1524)
				(type default)
			)
			(layer "F.SilkS")
		)
		(fp_line
			(start -0.7874 0.4064)
			(end -0.7874 -0.4064)
			(stroke
				(width 0.1524)
				(type default)
			)
			(layer "F.SilkS")
		)
		(fp_line
			(start 0.7874 -0.4064)
			(end 0.7874 0.4064)
			(stroke
				(width 0.1524)
				(type default)
			)
			(layer "F.SilkS")
		)
		(fp_line
			(start 0.7874 0.4064)
			(end -0.7874 0.4064)
			(stroke
				(width 0.1524)
				(type default)
			)
			(layer "F.SilkS")
		)
		(fp_line
			(start -0.67945 -0.305054)
			(end -0.12065 -0.305054)
			(stroke
				(width 0.1)
				(type default)
			)
			(layer "F.Fab")
		)
		(fp_line
			(start -0.67945 0.3048)
			(end -0.67945 -0.305054)
			(stroke
				(width 0.1)
				(type default)
			)
			(layer "F.Fab")
		)
		(fp_line
			(start -0.12065 -0.305054)
			(end -0.12065 -0.2794)
			(stroke
				(width 0.1)
				(type default)
			)
			(layer "F.Fab")
		)
		(fp_line
			(start -0.12065 -0.2794)
			(end 0.12065 -0.2794)
			(stroke
				(width 0.1)
				(type default)
			)
			(layer "F.Fab")
		)
		(fp_line
			(start -0.12065 0.2794)
			(end -0.12065 0.3048)
			(stroke
				(width 0.1)
				(type default)
			)
			(layer "F.Fab")
		)
		(fp_line
			(start -0.12065 0.3048)
			(end -0.67945 0.3048)
			(stroke
				(width 0.1)
				(type default)
			)
			(layer "F.Fab")
		)
		(fp_line
			(start 0.120396 0.2794)
			(end -0.12065 0.2794)
			(stroke
				(width 0.1)
				(type default)
			)
			(layer "F.Fab")
		)
		(fp_line
			(start 0.120396 0.3048)
			(end 0.120396 0.2794)
			(stroke
				(width 0.1)
				(type default)
			)
			(layer "F.Fab")
		)
		(fp_line
			(start 0.12065 -0.3048)
			(end 0.67945 -0.3048)
			(stroke
				(width 0.1)
				(type default)
			)
			(layer "F.Fab")
		)
		(fp_line
			(start 0.12065 -0.2794)
			(end 0.12065 -0.3048)
			(stroke
				(width 0.1)
				(type default)
			)
			(layer "F.Fab")
		)
		(fp_line
			(start 0.67945 -0.3048)
			(end 0.67945 0.3048)
			(stroke
				(width 0.1)
				(type default)
			)
			(layer "F.Fab")
		)
		(fp_line
			(start 0.67945 0.3048)
			(end 0.120396 0.3048)
			(stroke
				(width 0.1)
				(type default)
			)
			(layer "F.Fab")
		)
		(pad "1" smd circle
			(at -0.40005 0)
			(size 0 0)
			(layers "F.Cu" "F.Mask" "F.Paste")
			(net "P3V3_AUX")
		)
		(pad "2" smd circle
			(at 0.40005 0)
			(size 0 0)
			(layers "F.Cu" "F.Mask" "F.Paste")
			(net "USB_CPU0_ADD_A1")
		)
	)
	(footprint ""
		(layer "F.Cu")
		(at 69.493638 -386.44068 90)
		(property "Reference" "C117"
			(at 0 0 90)
			(layer "F.SilkS")
			(hide yes)
			(effects
				(font
					(size 1.27 1.27)
				)
			)
		)
		(property "Value" ""
			(at 0 0 90)
			(layer "F.Fab")
			(effects
				(font
					(size 1.27 1.27)
				)
			)
		)
		(duplicate_pad_numbers_are_jumpers no)
		(fp_line
			(start 0.7874 -0.4064)
			(end 0.7874 0.4064)
			(stroke
				(width 0.1524)
				(type default)
			)
			(layer "F.SilkS")
		)
		(fp_line
			(start -0.7874 -0.4064)
			(end 0.7874 -0.4064)
			(stroke
				(width 0.1524)
				(type default)
			)
			(layer "F.SilkS")
		)
		(fp_line
			(start 0.7874 0.4064)
			(end -0.7874 0.4064)
			(stroke
				(width 0.1524)
				(type default)
			)
			(layer "F.SilkS")
		)
		(fp_line
			(start -0.7874 0.4064)
			(end -0.7874 -0.4064)
			(stroke
				(width 0.1524)
				(type default)
			)
			(layer "F.SilkS")
		)
		(fp_line
			(start -0.12065 -0.305054)
			(end -0.12065 -0.2794)
			(stroke
				(width 0.1)
				(type default)
			)
			(layer "F.Fab")
		)
		(fp_line
			(start -0.67945 -0.305054)
			(end -0.12065 -0.305054)
			(stroke
				(width 0.1)
				(type default)
			)
			(layer "F.Fab")
		)
		(fp_line
			(start 0.67945 -0.3048)
			(end 0.67945 0.3048)
			(stroke
				(width 0.1)
				(type default)
			)
			(layer "F.Fab")
		)
		(fp_line
			(start 0.12065 -0.3048)
			(end 0.67945 -0.3048)
			(stroke
				(width 0.1)
				(type default)
			)
			(layer "F.Fab")
		)
		(fp_line
			(start 0.12065 -0.2794)
			(end 0.12065 -0.3048)
			(stroke
				(width 0.1)
				(type default)
			)
			(layer "F.Fab")
		)
		(fp_line
			(start -0.12065 -0.2794)
			(end 0.12065 -0.2794)
			(stroke
				(width 0.1)
				(type default)
			)
			(layer "F.Fab")
		)
		(fp_line
			(start 0.120396 0.2794)
			(end -0.12065 0.2794)
			(stroke
				(width 0.1)
				(type default)
			)
			(layer "F.Fab")
		)
		(fp_line
			(start -0.12065 0.2794)
			(end -0.12065 0.3048)
			(stroke
				(width 0.1)
				(type default)
			)
			(layer "F.Fab")
		)
		(fp_line
			(start 0.67945 0.3048)
			(end 0.120396 0.3048)
			(stroke
				(width 0.1)
				(type default)
			)
			(layer "F.Fab")
		)
		(fp_line
			(start 0.120396 0.3048)
			(end 0.120396 0.2794)
			(stroke
				(width 0.1)
				(type default)
			)
			(layer "F.Fab")
		)
		(fp_line
			(start -0.12065 0.3048)
			(end -0.67945 0.3048)
			(stroke
				(width 0.1)
				(type default)
			)
			(layer "F.Fab")
		)
		(fp_line
			(start -0.67945 0.3048)
			(end -0.67945 -0.305054)
			(stroke
				(width 0.1)
				(type default)
			)
			(layer "F.Fab")
		)
		(pad "1" smd circle
			(at -0.40005 0 90)
			(size 0 0)
			(layers "F.Cu" "F.Mask" "F.Paste")
			(net "P1V8_CPU1_RT0_1A")
		)
		(pad "2" smd circle
			(at 0.40005 0 90)
			(size 0 0)
			(layers "F.Cu" "F.Mask" "F.Paste")
			(net "GND")
		)
	)
	(footprint ""
		(layer "F.Cu")
		(at 270.312134 -421.23868 90)
		(property "Reference" "C1797"
			(at 0 0 90)
			(layer "F.SilkS")
			(hide yes)
			(effects
				(font
					(size 1.27 1.27)
				)
			)
		)
		(property "Value" ""
			(at 0 0 90)
			(layer "F.Fab")
			(effects
				(font
					(size 1.27 1.27)
				)
			)
		)
		(duplicate_pad_numbers_are_jumpers no)
		(fp_line
			(start 0.7874 -0.4064)
			(end 0.7874 0.4064)
			(stroke
				(width 0.1524)
				(type default)
			)
			(layer "F.SilkS")
		)
		(fp_line
			(start -0.7874 -0.4064)
			(end 0.7874 -0.4064)
			(stroke
				(width 0.1524)
				(type default)
			)
			(layer "F.SilkS")
		)
		(fp_line
			(start 0.7874 0.4064)
			(end -0.7874 0.4064)
			(stroke
				(width 0.1524)
				(type default)
			)
			(layer "F.SilkS")
		)
		(fp_line
			(start -0.7874 0.4064)
			(end -0.7874 -0.4064)
			(stroke
				(width 0.1524)
				(type default)
			)
			(layer "F.SilkS")
		)
		(fp_line
			(start -0.12065 -0.305054)
			(end -0.12065 -0.2794)
			(stroke
				(width 0.1)
				(type default)
			)
			(layer "F.Fab")
		)
		(fp_line
			(start -0.67945 -0.305054)
			(end -0.12065 -0.305054)
			(stroke
				(width 0.1)
				(type default)
			)
			(layer "F.Fab")
		)
		(fp_line
			(start 0.67945 -0.3048)
			(end 0.67945 0.3048)
			(stroke
				(width 0.1)
				(type default)
			)
			(layer "F.Fab")
		)
		(fp_line
			(start 0.12065 -0.3048)
			(end 0.67945 -0.3048)
			(stroke
				(width 0.1)
				(type default)
			)
			(layer "F.Fab")
		)
		(fp_line
			(start 0.12065 -0.2794)
			(end 0.12065 -0.3048)
			(stroke
				(width 0.1)
				(type default)
			)
			(layer "F.Fab")
		)
		(fp_line
			(start -0.12065 -0.2794)
			(end 0.12065 -0.2794)
			(stroke
				(width 0.1)
				(type default)
			)
			(layer "F.Fab")
		)
		(fp_line
			(start 0.120396 0.2794)
			(end -0.12065 0.2794)
			(stroke
				(width 0.1)
				(type default)
			)
			(layer "F.Fab")
		)
		(fp_line
			(start -0.12065 0.2794)
			(end -0.12065 0.3048)
			(stroke
				(width 0.1)
				(type default)
			)
			(layer "F.Fab")
		)
		(fp_line
			(start 0.67945 0.3048)
			(end 0.120396 0.3048)
			(stroke
				(width 0.1)
				(type default)
			)
			(layer "F.Fab")
		)
		(fp_line
			(start 0.120396 0.3048)
			(end 0.120396 0.2794)
			(stroke
				(width 0.1)
				(type default)
			)
			(layer "F.Fab")
		)
		(fp_line
			(start -0.12065 0.3048)
			(end -0.67945 0.3048)
			(stroke
				(width 0.1)
				(type default)
			)
			(layer "F.Fab")
		)
		(fp_line
			(start -0.67945 0.3048)
			(end -0.67945 -0.305054)
			(stroke
				(width 0.1)
				(type default)
			)
			(layer "F.Fab")
		)
		(pad "1" smd circle
			(at -0.40005 0 90)
			(size 0 0)
			(layers "F.Cu" "F.Mask" "F.Paste")
			(net "PDB_PRSNT_R_N")
		)
		(pad "2" smd circle
			(at 0.40005 0 90)
			(size 0 0)
			(layers "F.Cu" "F.Mask" "F.Paste")
			(net "GND")
		)
	)
	(footprint ""
		(layer "F.Cu")
		(at 119.349774 -165.109398 90)
		(property "Reference" "PC326_2"
			(at 0 0 90)
			(layer "F.SilkS")
			(hide yes)
			(effects
				(font
					(size 1.27 1.27)
				)
			)
		)
		(property "Value" ""
			(at 0 0 90)
			(layer "F.Fab")
			(effects
				(font
					(size 1.27 1.27)
				)
			)
		)
		(duplicate_pad_numbers_are_jumpers no)
		(fp_line
			(start 0.7874 -0.4064)
			(end 0.7874 0.4064)
			(stroke
				(width 0.1524)
				(type default)
			)
			(layer "F.SilkS")
		)
		(fp_line
			(start -0.7874 -0.4064)
			(end 0.7874 -0.4064)
			(stroke
				(width 0.1524)
				(type default)
			)
			(layer "F.SilkS")
		)
		(fp_line
			(start 0.7874 0.4064)
			(end -0.7874 0.4064)
			(stroke
				(width 0.1524)
				(type default)
			)
			(layer "F.SilkS")
		)
		(fp_line
			(start -0.7874 0.4064)
			(end -0.7874 -0.4064)
			(stroke
				(width 0.1524)
				(type default)
			)
			(layer "F.SilkS")
		)
		(fp_line
			(start -0.12065 -0.305054)
			(end -0.12065 -0.2794)
			(stroke
				(width 0.1)
				(type default)
			)
			(layer "F.Fab")
		)
		(fp_line
			(start -0.67945 -0.305054)
			(end -0.12065 -0.305054)
			(stroke
				(width 0.1)
				(type default)
			)
			(layer "F.Fab")
		)
		(fp_line
			(start 0.67945 -0.3048)
			(end 0.67945 0.3048)
			(stroke
				(width 0.1)
				(type default)
			)
			(layer "F.Fab")
		)
		(fp_line
			(start 0.12065 -0.3048)
			(end 0.67945 -0.3048)
			(stroke
				(width 0.1)
				(type default)
			)
			(layer "F.Fab")
		)
		(fp_line
			(start 0.12065 -0.2794)
			(end 0.12065 -0.3048)
			(stroke
				(width 0.1)
				(type default)
			)
			(layer "F.Fab")
		)
		(fp_line
			(start -0.12065 -0.2794)
			(end 0.12065 -0.2794)
			(stroke
				(width 0.1)
				(type default)
			)
			(layer "F.Fab")
		)
		(fp_line
			(start 0.120396 0.2794)
			(end -0.12065 0.2794)
			(stroke
				(width 0.1)
				(type default)
			)
			(layer "F.Fab")
		)
		(fp_line
			(start -0.12065 0.2794)
			(end -0.12065 0.3048)
			(stroke
				(width 0.1)
				(type default)
			)
			(layer "F.Fab")
		)
		(fp_line
			(start 0.67945 0.3048)
			(end 0.120396 0.3048)
			(stroke
				(width 0.1)
				(type default)
			)
			(layer "F.Fab")
		)
		(fp_line
			(start 0.120396 0.3048)
			(end 0.120396 0.2794)
			(stroke
				(width 0.1)
				(type default)
			)
			(layer "F.Fab")
		)
		(fp_line
			(start -0.12065 0.3048)
			(end -0.67945 0.3048)
			(stroke
				(width 0.1)
				(type default)
			)
			(layer "F.Fab")
		)
		(fp_line
			(start -0.67945 0.3048)
			(end -0.67945 -0.305054)
			(stroke
				(width 0.1)
				(type default)
			)
			(layer "F.Fab")
		)
		(pad "1" smd circle
			(at -0.40005 0 90)
			(size 0 0)
			(layers "F.Cu" "F.Mask" "F.Paste")
			(net "SW_P12V_AUX_PVDDCR_SOC_P1_FLT")
		)
		(pad "2" smd circle
			(at 0.40005 0 90)
			(size 0 0)
			(layers "F.Cu" "F.Mask" "F.Paste")
			(net "GND")
		)
	)
	(footprint ""
		(layer "F.Cu")
		(at 215.9 -97.79 180)
		(property "Reference" "R9031"
			(at 0 0 180)
			(layer "F.SilkS")
			(hide yes)
			(effects
				(font
					(size 1.27 1.27)
				)
			)
		)
		(property "Value" ""
			(at 0 0 180)
			(layer "F.Fab")
			(effects
				(font
					(size 1.27 1.27)
				)
			)
		)
		(duplicate_pad_numbers_are_jumpers no)
		(fp_line
			(start 0.7874 0.4064)
			(end -0.7874 0.4064)
			(stroke
				(width 0.1524)
				(type default)
			)
			(layer "F.SilkS")
		)
		(fp_line
			(start 0.7874 -0.4064)
			(end 0.7874 0.4064)
			(stroke
				(width 0.1524)
				(type default)
			)
			(layer "F.SilkS")
		)
		(fp_line
			(start -0.7874 0.4064)
			(end -0.7874 -0.4064)
			(stroke
				(width 0.1524)
				(type default)
			)
			(layer "F.SilkS")
		)
		(fp_line
			(start -0.7874 -0.4064)
			(end 0.7874 -0.4064)
			(stroke
				(width 0.1524)
				(type default)
			)
			(layer "F.SilkS")
		)
		(fp_line
			(start 0.67945 0.3048)
			(end 0.120396 0.3048)
			(stroke
				(width 0.1)
				(type default)
			)
			(layer "F.Fab")
		)
		(fp_line
			(start 0.67945 -0.3048)
			(end 0.67945 0.3048)
			(stroke
				(width 0.1)
				(type default)
			)
			(layer "F.Fab")
		)
		(fp_line
			(start 0.12065 -0.2794)
			(end 0.12065 -0.3048)
			(stroke
				(width 0.1)
				(type default)
			)
			(layer "F.Fab")
		)
		(fp_line
			(start 0.12065 -0.3048)
			(end 0.67945 -0.3048)
			(stroke
				(width 0.1)
				(type default)
			)
			(layer "F.Fab")
		)
		(fp_line
			(start 0.120396 0.3048)
			(end 0.120396 0.2794)
			(stroke
				(width 0.1)
				(type default)
			)
			(layer "F.Fab")
		)
		(fp_line
			(start 0.120396 0.2794)
			(end -0.12065 0.2794)
			(stroke
				(width 0.1)
				(type default)
			)
			(layer "F.Fab")
		)
		(fp_line
			(start -0.12065 0.3048)
			(end -0.67945 0.3048)
			(stroke
				(width 0.1)
				(type default)
			)
			(layer "F.Fab")
		)
		(fp_line
			(start -0.12065 0.2794)
			(end -0.12065 0.3048)
			(stroke
				(width 0.1)
				(type default)
			)
			(layer "F.Fab")
		)
		(fp_line
			(start -0.12065 -0.2794)
			(end 0.12065 -0.2794)
			(stroke
				(width 0.1)
				(type default)
			)
			(layer "F.Fab")
		)
		(fp_line
			(start -0.12065 -0.305054)
			(end -0.12065 -0.2794)
			(stroke
				(width 0.1)
				(type default)
			)
			(layer "F.Fab")
		)
		(fp_line
			(start -0.67945 0.3048)
			(end -0.67945 -0.305054)
			(stroke
				(width 0.1)
				(type default)
			)
			(layer "F.Fab")
		)
		(fp_line
			(start -0.67945 -0.305054)
			(end -0.12065 -0.305054)
			(stroke
				(width 0.1)
				(type default)
			)
			(layer "F.Fab")
		)
		(pad "1" smd circle
			(at -0.40005 0 180)
			(size 0 0)
			(layers "F.Cu" "F.Mask" "F.Paste")
			(net "OCP_SFF_AUX_PWR_EN_R3")
		)
		(pad "2" smd circle
			(at 0.40005 0 180)
			(size 0 0)
			(layers "F.Cu" "F.Mask" "F.Paste")
			(net "OCP_SFF_AUX_PWR_EN")
		)
	)
)
